# S9S_MB_2U (Grand Teton) — schematic netlist excerpt (pin names and nets, part order shuffled) for the footprints in the layout excerpt that follows; sources: Cadence DE-HDL packaged netlist, KiCad conversion of 03242023_DA0F0TMBIJ0_F0T_Motherboard_J_brd_V01_OCP.brd

R3493  Q_RES  100K 1% EMPTY  pkg 0402LF  page 150 : A = GPU_FPGA_EROT_RST_BUF_R_N ; B = GND
PR1774  Q_RES  3.3 1% CHIP  pkg 0402LF  page 275 : A = SW_PVCCINFAON_CPU0_BOOT1 ; B = SW_PVCCINFAON_CPU0_BOOT1_R

(kicad_pcb
	(version 20260206)
	(generator "pcbnew")
	(generator_version "10.0")
	(general
		(thickness 1.6)
		(legacy_teardrops no)
	)
	(paper "A4")
	(title_block
		(title "03242023_DA0F0TMBIJ0_F0T_Motherboard_J_brd_V01_OCP.brd")
		(comment 1 "Grand Teton / footprints 3870-3871 of 6105")
	)
	(layers
		(0 "F.Cu" signal "TOP")
		(4 "In1.Cu" signal "GND")
		(6 "In2.Cu" signal "IN1")
		(8 "In3.Cu" signal "GND1")
		(10 "In4.Cu" signal "IN2")
		(12 "In5.Cu" signal "GND2")
		(14 "In6.Cu" signal "IN3")
		(16 "In7.Cu" signal "GND3")
		(18 "In8.Cu" signal "VCC")
		(20 "In9.Cu" signal "VCC1")
		(22 "In10.Cu" signal "GND4")
		(24 "In11.Cu" signal "IN4")
		(26 "In12.Cu" signal "GND5")
		(28 "In13.Cu" signal "IN5")
		(30 "In14.Cu" signal "GND6")
		(32 "In15.Cu" signal "IN6")
		(34 "In16.Cu" signal "GND7")
		(2 "B.Cu" signal "BOTTOM")
		(9 "F.Adhes" user "F.Adhesive")
		(11 "B.Adhes" user "B.Adhesive")
		(13 "F.Paste" user "Package Geometry/Pastemask Top")
		(15 "B.Paste" user "Package Geometry/Pastemask Bottom")
		(5 "F.SilkS" user "Ref Des/Silkscreen Top")
		(7 "B.SilkS" user "Ref Des/Silkscreen Bottom")
		(1 "F.Mask" user "Board Geometry/Soldermask Top")
		(3 "B.Mask" user "Board Geometry/Soldermask Bottom")
		(17 "Dwgs.User" user "User.Drawings")
		(19 "Cmts.User" user "User.Comments")
		(21 "Eco1.User" user "User.Eco1")
		(23 "Eco2.User" user "User.Eco2")
		(25 "Edge.Cuts" user "Board Geometry/Outline")
		(27 "Margin" user)
		(31 "F.CrtYd" user "Package Geometry/Place Bound Top")
		(29 "B.CrtYd" user "Package Geometry/Place Bound Bottom")
		(35 "F.Fab" user "Ref Des/Assembly Top")
		(33 "B.Fab" user "Ref Des/Assembly Bottom")
	)
	(footprint ""
		(layer "F.Cu")
		(at 420.473632 -170.126914)
		(property "Reference" "PR1774"
			(at 0 0 0)
			(layer "F.SilkS")
			(hide yes)
			(effects
				(font
					(size 1.27 1.27)
				)
			)
		)
		(property "Value" ""
			(at 0 0 0)
			(layer "F.Fab")
			(effects
				(font
					(size 1.27 1.27)
				)
			)
		)
		(duplicate_pad_numbers_are_jumpers no)
		(fp_line
			(start -0.7874 -0.4064)
			(end 0.7874 -0.4064)
			(stroke
				(width 0.1524)
				(type default)
			)
			(layer "F.SilkS")
		)
		(fp_line
			(start -0.7874 0.4064)
			(end -0.7874 -0.4064)
			(stroke
				(width 0.1524)
				(type default)
			)
			(layer "F.SilkS")
		)
		(fp_line
			(start 0.7874 -0.4064)
			(end 0.7874 0.4064)
			(stroke
				(width 0.1524)
				(type default)
			)
			(layer "F.SilkS")
		)
		(fp_line
			(start 0.7874 0.4064)
			(end -0.7874 0.4064)
			(stroke
				(width 0.1524)
				(type default)
			)
			(layer "F.SilkS")
		)
		(fp_line
			(start -0.67945 -0.305054)
			(end -0.12065 -0.305054)
			(stroke
				(width 0.1)
				(type default)
			)
			(layer "F.Fab")
		)
		(fp_line
			(start -0.67945 0.3048)
			(end -0.67945 -0.305054)
			(stroke
				(width 0.1)
				(type default)
			)
			(layer "F.Fab")
		)
		(fp_line
			(start -0.12065 -0.305054)
			(end -0.12065 -0.2794)
			(stroke
				(width 0.1)
				(type default)
			)
			(layer "F.Fab")
		)
		(fp_line
			(start -0.12065 -0.2794)
			(end 0.12065 -0.2794)
			(stroke
				(width 0.1)
				(type default)
			)
			(layer "F.Fab")
		)
		(fp_line
			(start -0.12065 0.2794)
			(end -0.12065 0.3048)
			(stroke
				(width 0.1)
				(type default)
			)
			(layer "F.Fab")
		)
		(fp_line
			(start -0.12065 0.3048)
			(end -0.67945 0.3048)
			(stroke
				(width 0.1)
				(type default)
			)
			(layer "F.Fab")
		)
		(fp_line
			(start 0.120396 0.2794)
			(end -0.12065 0.2794)
			(stroke
				(width 0.1)
				(type default)
			)
			(layer "F.Fab")
		)
		(fp_line
			(start 0.120396 0.3048)
			(end 0.120396 0.2794)
			(stroke
				(width 0.1)
				(type default)
			)
			(layer "F.Fab")
		)
		(fp_line
			(start 0.12065 -0.3048)
			(end 0.67945 -0.3048)
			(stroke
				(width 0.1)
				(type default)
			)
			(layer "F.Fab")
		)
		(fp_line
			(start 0.12065 -0.2794)
			(end 0.12065 -0.3048)
			(stroke
				(width 0.1)
				(type default)
			)
			(layer "F.Fab")
		)
		(fp_line
			(start 0.67945 -0.3048)
			(end 0.67945 0.3048)
			(stroke
				(width 0.1)
				(type default)
			)
			(layer "F.Fab")
		)
		(fp_line
			(start 0.67945 0.3048)
			(end 0.120396 0.3048)
			(stroke
				(width 0.1)
				(type default)
			)
			(layer "F.Fab")
		)
		(pad "1" smd circle
			(at -0.40005 0)
			(size 0 0)
			(layers "F.Cu" "F.Mask" "F.Paste")
			(net "SW_PVCCINFAON_CPU0_BOOT1")
		)
		(pad "2" smd circle
			(at 0.40005 0)
			(size 0 0)
			(layers "F.Cu" "F.Mask" "F.Paste")
			(net "SW_PVCCINFAON_CPU0_BOOT1_R")
		)
	)
	(footprint ""
		(layer "F.Cu")
		(at 101.833934 -396.44574 180)
		(property "Reference" "R3493"
			(at 0 0 180)
			(layer "F.SilkS")
			(hide yes)
			(effects
				(font
					(size 1.27 1.27)
				)
			)
		)
		(property "Value" ""
			(at 0 0 180)
			(layer "F.Fab")
			(effects
				(font
					(size 1.27 1.27)
				)
			)
		)
		(duplicate_pad_numbers_are_jumpers no)
		(fp_line
			(start 0.7874 0.4064)
			(end -0.7874 0.4064)
			(stroke
				(width 0.1524)
				(type default)
			)
			(layer "F.SilkS")
		)
		(fp_line
			(start 0.7874 -0.4064)
			(end 0.7874 0.4064)
			(stroke
				(width 0.1524)
				(type default)
			)
			(layer "F.SilkS")
		)
		(fp_line
			(start -0.7874 0.4064)
			(end -0.7874 -0.4064)
			(stroke
				(width 0.1524)
				(type default)
			)
			(layer "F.SilkS")
		)
		(fp_line
			(start -0.7874 -0.4064)
			(end 0.7874 -0.4064)
			(stroke
				(width 0.1524)
				(type default)
			)
			(layer "F.SilkS")
		)
		(fp_line
			(start 0.67945 0.3048)
			(end 0.120396 0.3048)
			(stroke
				(width 0.1)
				(type default)
			)
			(layer "F.Fab")
		)
		(fp_line
			(start 0.67945 -0.3048)
			(end 0.67945 0.3048)
			(stroke
				(width 0.1)
				(type default)
			)
			(layer "F.Fab")
		)
		(fp_line
			(start 0.12065 -0.2794)
			(end 0.12065 -0.3048)
			(stroke
				(width 0.1)
				(type default)
			)
			(layer "F.Fab")
		)
		(fp_line
			(start 0.12065 -0.3048)
			(end 0.67945 -0.3048)
			(stroke
				(width 0.1)
				(type default)
			)
			(layer "F.Fab")
		)
		(fp_line
			(start 0.120396 0.3048)
			(end 0.120396 0.2794)
			(stroke
				(width 0.1)
				(type default)
			)
			(layer "F.Fab")
		)
		(fp_line
			(start 0.120396 0.2794)
			(end -0.12065 0.2794)
			(stroke
				(width 0.1)
				(type default)
			)
			(layer "F.Fab")
		)
		(fp_line
			(start -0.12065 0.3048)
			(end -0.67945 0.3048)
			(stroke
				(width 0.1)
				(type default)
			)
			(layer "F.Fab")
		)
		(fp_line
			(start -0.12065 0.2794)
			(end -0.12065 0.3048)
			(stroke
				(width 0.1)
				(type default)
			)
			(layer "F.Fab")
		)
		(fp_line
			(start -0.12065 -0.2794)
			(end 0.12065 -0.2794)
			(stroke
				(width 0.1)
				(type default)
			)
			(layer "F.Fab")
		)
		(fp_line
			(start -0.12065 -0.305054)
			(end -0.12065 -0.2794)
			(stroke
				(width 0.1)
				(type default)
			)
			(layer "F.Fab")
		)
		(fp_line
			(start -0.67945 0.3048)
			(end -0.67945 -0.305054)
			(stroke
				(width 0.1)
				(type default)
			)
			(layer "F.Fab")
		)
		(fp_line
			(start -0.67945 -0.305054)
			(end -0.12065 -0.305054)
			(stroke
				(width 0.1)
				(type default)
			)
			(layer "F.Fab")
		)
		(pad "1" smd circle
			(at -0.40005 0 180)
			(size 0 0)
			(layers "F.Cu" "F.Mask" "F.Paste")
			(net "GPU_FPGA_EROT_RST_BUF_R_N")
		)
		(pad "2" smd circle
			(at 0.40005 0 180)
			(size 0 0)
			(layers "F.Cu" "F.Mask" "F.Paste")
			(net "GND")
		)
	)
)
